(kicad_pcb
	(version 20260206)
	(generator "pcbnew")
	(generator_version "10.0")
	(general
		(thickness 1.6)
		(legacy_teardrops no)
	)
	(paper "A4")
	(title_block
		(title "03242023_DA0F0TMBIJ0_F0T_Motherboard_J_brd_V01_OCP.brd")
		(comment 1 "Grand Teton / footprints 5336-5341 of 6105")
	)
	(layers
		(0 "F.Cu" signal "TOP")
		(4 "In1.Cu" signal "GND")
		(6 "In2.Cu" signal "IN1")
		(8 "In3.Cu" signal "GND1")
		(10 "In4.Cu" signal "IN2")
		(12 "In5.Cu" signal "GND2")
		(14 "In6.Cu" signal "IN3")
		(16 "In7.Cu" signal "GND3")
		(18 "In8.Cu" signal "VCC")
		(20 "In9.Cu" signal "VCC1")
		(22 "In10.Cu" signal "GND4")
		(24 "In11.Cu" signal "IN4")
		(26 "In12.Cu" signal "GND5")
		(28 "In13.Cu" signal "IN5")
		(30 "In14.Cu" signal "GND6")
		(32 "In15.Cu" signal "IN6")
		(34 "In16.Cu" signal "GND7")
		(2 "B.Cu" signal "BOTTOM")
		(9 "F.Adhes" user "F.Adhesive")
		(11 "B.Adhes" user "B.Adhesive")
		(13 "F.Paste" user "Package Geometry/Pastemask Top")
		(15 "B.Paste" user "Package Geometry/Pastemask Bottom")
		(5 "F.SilkS" user "Ref Des/Silkscreen Top")
		(7 "B.SilkS" user "Ref Des/Silkscreen Bottom")
		(1 "F.Mask" user "Board Geometry/Soldermask Top")
		(3 "B.Mask" user "Board Geometry/Soldermask Bottom")
		(17 "Dwgs.User" user "User.Drawings")
		(19 "Cmts.User" user "User.Comments")
		(21 "Eco1.User" user "User.Eco1")
		(23 "Eco2.User" user "User.Eco2")
		(25 "Edge.Cuts" user "Board Geometry/Outline")
		(27 "Margin" user)
		(31 "F.CrtYd" user "Package Geometry/Place Bound Top")
		(29 "B.CrtYd" user "Package Geometry/Place Bound Bottom")
		(35 "F.Fab" user "Ref Des/Assembly Top")
		(33 "B.Fab" user "Ref Des/Assembly Bottom")
	)
	(footprint ""
		(layer "B.Cu")
		(at 38.335458 -315.46673 -90)
		(property "Reference" "D47"
			(at 3.662172 3.237738 0)
			(unlocked yes)
			(layer "B.SilkS")
			(effects
				(font
					(size 0.7874 0.5842)
					(thickness 0.1524)
				)
				(justify left mirror)
			)
		)
		(property "Value" ""
			(at 0 0 90)
			(layer "B.Fab")
			(effects
				(font
					(size 1.27 1.27)
				)
				(justify mirror)
			)
		)
		(duplicate_pad_numbers_are_jumpers no)
		(fp_line
			(start -2.050796 0.700024)
			(end 2.050796 0.700024)
			(stroke
				(width 0.1524)
				(type default)
			)
			(layer "B.SilkS")
		)
		(fp_line
			(start 2.050796 0.700024)
			(end 2.050796 -0.700024)
			(stroke
				(width 0.1524)
				(type default)
			)
			(layer "B.SilkS")
		)
		(fp_line
			(start -2.343404 0.6985)
			(end -2.216404 0.6985)
			(stroke
				(width 0.1524)
				(type default)
			)
			(layer "B.SilkS")
		)
		(fp_line
			(start -2.229104 0.6985)
			(end -2.051304 0.6985)
			(stroke
				(width 0.1524)
				(type default)
			)
			(layer "B.SilkS")
		)
		(fp_line
			(start -2.051304 0.6985)
			(end -2.051304 0.635)
			(stroke
				(width 0.1524)
				(type default)
			)
			(layer "B.SilkS")
		)
		(fp_line
			(start -2.152904 0.635)
			(end -2.152904 -0.6985)
			(stroke
				(width 0.1524)
				(type default)
			)
			(layer "B.SilkS")
		)
		(fp_line
			(start -2.051304 0.635)
			(end -2.152904 0.635)
			(stroke
				(width 0.1524)
				(type default)
			)
			(layer "B.SilkS")
		)
		(fp_line
			(start 0.30607 0.500126)
			(end -0.193802 0)
			(stroke
				(width 0.1524)
				(type default)
			)
			(layer "B.SilkS")
		)
		(fp_line
			(start -0.193802 0)
			(end 0.30607 -0.500126)
			(stroke
				(width 0.1524)
				(type default)
			)
			(layer "B.SilkS")
		)
		(fp_line
			(start -0.293878 -0.500126)
			(end -0.293878 0.500126)
			(stroke
				(width 0.1524)
				(type default)
			)
			(layer "B.SilkS")
		)
		(fp_line
			(start 0.30607 -0.500126)
			(end 0.30607 0.500126)
			(stroke
				(width 0.1524)
				(type default)
			)
			(layer "B.SilkS")
		)
		(fp_line
			(start -2.064004 -0.6731)
			(end -2.064004 -0.6985)
			(stroke
				(width 0.1524)
				(type default)
			)
			(layer "B.SilkS")
		)
		(fp_line
			(start -2.343404 -0.6985)
			(end -2.343404 0.6985)
			(stroke
				(width 0.1524)
				(type default)
			)
			(layer "B.SilkS")
		)
		(fp_line
			(start -2.229104 -0.6985)
			(end -2.229104 0.6985)
			(stroke
				(width 0.1524)
				(type default)
			)
			(layer "B.SilkS")
		)
		(fp_line
			(start -2.152904 -0.6985)
			(end -2.343404 -0.6985)
			(stroke
				(width 0.1524)
				(type default)
			)
			(layer "B.SilkS")
		)
		(fp_line
			(start -2.064004 -0.6985)
			(end -2.229104 -0.6985)
			(stroke
				(width 0.1524)
				(type default)
			)
			(layer "B.SilkS")
		)
		(fp_line
			(start -2.050796 -0.700024)
			(end -2.050796 0.700024)
			(stroke
				(width 0.1524)
				(type default)
			)
			(layer "B.SilkS")
		)
		(fp_line
			(start 2.050796 -0.700024)
			(end -2.050796 -0.700024)
			(stroke
				(width 0.1524)
				(type default)
			)
			(layer "B.SilkS")
		)
		(fp_line
			(start -0.899922 0.700024)
			(end 0.899922 0.700024)
			(stroke
				(width 0.1)
				(type default)
			)
			(layer "B.Fab")
		)
		(fp_line
			(start 0.899922 0.700024)
			(end 0.899922 -0.700024)
			(stroke
				(width 0.1)
				(type default)
			)
			(layer "B.Fab")
		)
		(fp_line
			(start -0.899922 -0.700024)
			(end -0.899922 0.700024)
			(stroke
				(width 0.1)
				(type default)
			)
			(layer "B.Fab")
		)
		(fp_line
			(start 0.899922 -0.700024)
			(end -0.899922 -0.700024)
			(stroke
				(width 0.1)
				(type default)
			)
			(layer "B.Fab")
		)
		(fp_text user "-"
			(at -0.138938 1.966468 90)
			(unlocked yes)
			(layer "B.SilkS")
			(effects
				(font
					(size 1.905 1.4224)
					(thickness 0.1524)
				)
				(justify left mirror)
			)
		)
		(fp_text user "+"
			(at 3.123946 0.762 180)
			(unlocked yes)
			(layer "B.SilkS")
			(effects
				(font
					(size 1.905 1.4224)
					(thickness 0.1524)
				)
				(justify left mirror)
			)
		)
		(fp_text user "+"
			(at 3.123946 0.762 180)
			(unlocked yes)
			(layer "B.Fab")
			(effects
				(font
					(size 1.905 1.4224)
					(thickness 0.1524)
				)
				(justify left mirror)
			)
		)
		(fp_text user "-"
			(at -3.880104 0.23495 90)
			(unlocked yes)
			(layer "B.Fab")
			(effects
				(font
					(size 1.905 1.4224)
					(thickness 0.1524)
				)
				(justify left mirror)
			)
		)
		(pad "1" smd rect
			(at 1.199896 0 180)
			(size 0.6604 1.3716)
			(layers "B.Cu" "B.Mask" "B.Paste")
			(net "PWRGD_FAIL_CPU1_CD_R1")
		)
		(pad "2" smd rect
			(at -1.199896 0)
			(size 0.6604 1.3716)
			(layers "B.Cu" "B.Mask" "B.Paste")
			(net "P3V3_AUX")
		)
	)
	(footprint ""
		(layer "B.Cu")
		(at 105.670604 -296.05478)
		(property "Reference" "C344"
			(at 0 0 0)
			(layer "B.SilkS")
			(hide yes)
			(effects
				(font
					(size 1.27 1.27)
				)
				(justify mirror)
			)
		)
		(property "Value" ""
			(at 0 0 0)
			(layer "B.Fab")
			(effects
				(font
					(size 1.27 1.27)
				)
				(justify mirror)
			)
		)
		(duplicate_pad_numbers_are_jumpers no)
		(fp_line
			(start -1.524 -0.762)
			(end -1.524 0.762)
			(stroke
				(width 0.1524)
				(type default)
			)
			(layer "B.SilkS")
		)
		(fp_line
			(start -1.524 0.762)
			(end 1.524 0.762)
			(stroke
				(width 0.1524)
				(type default)
			)
			(layer "B.SilkS")
		)
		(fp_line
			(start 1.524 -0.762)
			(end -1.524 -0.762)
			(stroke
				(width 0.1524)
				(type default)
			)
			(layer "B.SilkS")
		)
		(fp_line
			(start 1.524 0.762)
			(end 1.524 -0.762)
			(stroke
				(width 0.1524)
				(type default)
			)
			(layer "B.SilkS")
		)
		(fp_line
			(start -1.1049 -0.724916)
			(end 1.1049 -0.724916)
			(stroke
				(width 0.1)
				(type default)
			)
			(layer "B.Fab")
		)
		(fp_line
			(start -1.1049 0.724916)
			(end -1.1049 -0.724916)
			(stroke
				(width 0.1)
				(type default)
			)
			(layer "B.Fab")
		)
		(fp_line
			(start 1.1049 -0.724916)
			(end 1.1049 0.724916)
			(stroke
				(width 0.1)
				(type default)
			)
			(layer "B.Fab")
		)
		(fp_line
			(start 1.1049 0.724916)
			(end -1.1049 0.724916)
			(stroke
				(width 0.1)
				(type default)
			)
			(layer "B.Fab")
		)
		(pad "1" smd rect
			(at 0.889 0)
			(size 1.016 1.27)
			(layers "B.Cu" "B.Mask" "B.Paste")
			(net "PVCCIN_CPU1")
		)
		(pad "2" smd rect
			(at -0.889 0)
			(size 1.016 1.27)
			(layers "B.Cu" "B.Mask" "B.Paste")
			(net "GND")
		)
	)
	(footprint ""
		(layer "B.Cu")
		(at 76.413106 -332.627224 90)
		(property "Reference" "PR578"
			(at 0 0 90)
			(layer "B.SilkS")
			(hide yes)
			(effects
				(font
					(size 1.27 1.27)
				)
				(justify mirror)
			)
		)
		(property "Value" ""
			(at 0 0 90)
			(layer "B.Fab")
			(effects
				(font
					(size 1.27 1.27)
				)
				(justify mirror)
			)
		)
		(duplicate_pad_numbers_are_jumpers no)
		(fp_line
			(start 0.7874 -0.4064)
			(end -0.7874 -0.4064)
			(stroke
				(width 0.1524)
				(type default)
			)
			(layer "B.SilkS")
		)
		(fp_line
			(start -0.7874 -0.4064)
			(end -0.7874 0.4064)
			(stroke
				(width 0.1524)
				(type default)
			)
			(layer "B.SilkS")
		)
		(fp_line
			(start 0.7874 0.4064)
			(end 0.7874 -0.4064)
			(stroke
				(width 0.1524)
				(type default)
			)
			(layer "B.SilkS")
		)
		(fp_line
			(start -0.7874 0.4064)
			(end 0.7874 0.4064)
			(stroke
				(width 0.1524)
				(type default)
			)
			(layer "B.SilkS")
		)
		(fp_line
			(start 0.67945 -0.305054)
			(end 0.12065 -0.305054)
			(stroke
				(width 0.1)
				(type default)
			)
			(layer "B.Fab")
		)
		(fp_line
			(start 0.12065 -0.305054)
			(end 0.12065 -0.2794)
			(stroke
				(width 0.1)
				(type default)
			)
			(layer "B.Fab")
		)
		(fp_line
			(start -0.12065 -0.3048)
			(end -0.67945 -0.3048)
			(stroke
				(width 0.1)
				(type default)
			)
			(layer "B.Fab")
		)
		(fp_line
			(start -0.67945 -0.3048)
			(end -0.67945 0.3048)
			(stroke
				(width 0.1)
				(type default)
			)
			(layer "B.Fab")
		)
		(fp_line
			(start 0.12065 -0.2794)
			(end -0.12065 -0.2794)
			(stroke
				(width 0.1)
				(type default)
			)
			(layer "B.Fab")
		)
		(fp_line
			(start -0.12065 -0.2794)
			(end -0.12065 -0.3048)
			(stroke
				(width 0.1)
				(type default)
			)
			(layer "B.Fab")
		)
		(fp_line
			(start 0.12065 0.2794)
			(end 0.12065 0.3048)
			(stroke
				(width 0.1)
				(type default)
			)
			(layer "B.Fab")
		)
		(fp_line
			(start -0.120396 0.2794)
			(end 0.12065 0.2794)
			(stroke
				(width 0.1)
				(type default)
			)
			(layer "B.Fab")
		)
		(fp_line
			(start 0.67945 0.3048)
			(end 0.67945 -0.305054)
			(stroke
				(width 0.1)
				(type default)
			)
			(layer "B.Fab")
		)
		(fp_line
			(start 0.12065 0.3048)
			(end 0.67945 0.3048)
			(stroke
				(width 0.1)
				(type default)
			)
			(layer "B.Fab")
		)
		(fp_line
			(start -0.120396 0.3048)
			(end -0.120396 0.2794)
			(stroke
				(width 0.1)
				(type default)
			)
			(layer "B.Fab")
		)
		(fp_line
			(start -0.67945 0.3048)
			(end -0.120396 0.3048)
			(stroke
				(width 0.1)
				(type default)
			)
			(layer "B.Fab")
		)
		(pad "1" smd circle
			(at 0.40005 0 270)
			(size 0 0)
			(layers "B.Cu" "B.Mask" "B.Paste")
			(net "VSENSE_PVCCIN_CPU1_DP")
		)
		(pad "2" smd circle
			(at -0.40005 0 270)
			(size 0 0)
			(layers "B.Cu" "B.Mask" "B.Paste")
			(net "PVCCIN_CPU1")
		)
	)
	(footprint ""
		(layer "B.Cu")
		(at 183.755538 -105.375456 90)
		(property "Reference" "C1124"
			(at 0 0 90)
			(layer "B.SilkS")
			(hide yes)
			(effects
				(font
					(size 1.27 1.27)
				)
				(justify mirror)
			)
		)
		(property "Value" ""
			(at 0 0 90)
			(layer "B.Fab")
			(effects
				(font
					(size 1.27 1.27)
				)
				(justify mirror)
			)
		)
		(duplicate_pad_numbers_are_jumpers no)
		(fp_line
			(start 0.69215 -0.2921)
			(end -0.69215 -0.2921)
			(stroke
				(width 0.1524)
				(type default)
			)
			(layer "B.SilkS")
		)
		(fp_line
			(start -0.69215 -0.2921)
			(end -0.69215 0.2921)
			(stroke
				(width 0.1524)
				(type default)
			)
			(layer "B.SilkS")
		)
		(fp_line
			(start 0.69215 0.2921)
			(end 0.69215 -0.2921)
			(stroke
				(width 0.1524)
				(type default)
			)
			(layer "B.SilkS")
		)
		(fp_line
			(start -0.69215 0.2921)
			(end 0.69215 0.2921)
			(stroke
				(width 0.1524)
				(type default)
			)
			(layer "B.SilkS")
		)
		(fp_line
			(start 0.51435 -0.2794)
			(end -0.51435 -0.2794)
			(stroke
				(width 0.1)
				(type default)
			)
			(layer "B.Fab")
		)
		(fp_line
			(start -0.51435 -0.2794)
			(end -0.51435 0.2794)
			(stroke
				(width 0.1)
				(type default)
			)
			(layer "B.Fab")
		)
		(fp_line
			(start 0.51435 0.2794)
			(end 0.51435 -0.2794)
			(stroke
				(width 0.1)
				(type default)
			)
			(layer "B.Fab")
		)
		(fp_line
			(start -0.51435 0.2794)
			(end 0.51435 0.2794)
			(stroke
				(width 0.1)
				(type default)
			)
			(layer "B.Fab")
		)
		(pad "1" smd circle
			(at 0.40005 0 270)
			(size 0 0)
			(layers "B.Cu" "B.Mask" "B.Paste")
			(net "P3V3_AUX_FPGA_VCCIO3")
		)
		(pad "2" smd circle
			(at -0.40005 0 270)
			(size 0 0)
			(layers "B.Cu" "B.Mask" "B.Paste")
			(net "GND")
		)
		(zone
			(layer "B.Cu")
			(hatch none 0.5)
			(connect_pads
				(clearance 0)
			)
			(min_thickness 0.25)
			(keepout
				(tracks not_allowed)
				(vias allowed)
				(pads allowed)
				(copperpour not_allowed)
				(footprints allowed)
			)
			(placement
				(enabled no)
				(sheetname "")
			)
			(fill
				(thermal_gap 0.5)
				(thermal_bridge_width 0.5)
				(island_removal_mode 0)
			)
			(polygon
				(pts
					(xy 183.843168 -105.565956) (xy 183.901334 -105.474516) (xy 183.901334 -105.275126) (xy 183.843168 -105.184956)
					(xy 183.667908 -105.184956) (xy 183.609488 -105.275126) (xy 183.609488 -105.474516) (xy 183.667654 -105.565956)
				)
			)
		)
	)
	(footprint ""
		(layer "B.Cu")
		(at 197.41388 -106.225848)
		(property "Reference" "R2347"
			(at 0 0 0)
			(layer "B.SilkS")
			(hide yes)
			(effects
				(font
					(size 1.27 1.27)
				)
				(justify mirror)
			)
		)
		(property "Value" ""
			(at 0 0 0)
			(layer "B.Fab")
			(effects
				(font
					(size 1.27 1.27)
				)
				(justify mirror)
			)
		)
		(duplicate_pad_numbers_are_jumpers no)
		(fp_line
			(start -0.7874 -0.4064)
			(end -0.7874 0.4064)
			(stroke
				(width 0.1524)
				(type default)
			)
			(layer "B.SilkS")
		)
		(fp_line
			(start -0.7874 0.4064)
			(end 0.7874 0.4064)
			(stroke
				(width 0.1524)
				(type default)
			)
			(layer "B.SilkS")
		)
		(fp_line
			(start 0.7874 -0.4064)
			(end -0.7874 -0.4064)
			(stroke
				(width 0.1524)
				(type default)
			)
			(layer "B.SilkS")
		)
		(fp_line
			(start 0.7874 0.4064)
			(end 0.7874 -0.4064)
			(stroke
				(width 0.1524)
				(type default)
			)
			(layer "B.SilkS")
		)
		(fp_line
			(start -0.67945 -0.3048)
			(end -0.67945 0.3048)
			(stroke
				(width 0.1)
				(type default)
			)
			(layer "B.Fab")
		)
		(fp_line
			(start -0.67945 0.3048)
			(end -0.120396 0.3048)
			(stroke
				(width 0.1)
				(type default)
			)
			(layer "B.Fab")
		)
		(fp_line
			(start -0.12065 -0.3048)
			(end -0.67945 -0.3048)
			(stroke
				(width 0.1)
				(type default)
			)
			(layer "B.Fab")
		)
		(fp_line
			(start -0.12065 -0.2794)
			(end -0.12065 -0.3048)
			(stroke
				(width 0.1)
				(type default)
			)
			(layer "B.Fab")
		)
		(fp_line
			(start -0.120396 0.2794)
			(end 0.12065 0.2794)
			(stroke
				(width 0.1)
				(type default)
			)
			(layer "B.Fab")
		)
		(fp_line
			(start -0.120396 0.3048)
			(end -0.120396 0.2794)
			(stroke
				(width 0.1)
				(type default)
			)
			(layer "B.Fab")
		)
		(fp_line
			(start 0.12065 -0.305054)
			(end 0.12065 -0.2794)
			(stroke
				(width 0.1)
				(type default)
			)
			(layer "B.Fab")
		)
		(fp_line
			(start 0.12065 -0.2794)
			(end -0.12065 -0.2794)
			(stroke
				(width 0.1)
				(type default)
			)
			(layer "B.Fab")
		)
		(fp_line
			(start 0.12065 0.2794)
			(end 0.12065 0.3048)
			(stroke
				(width 0.1)
				(type default)
			)
			(layer "B.Fab")
		)
		(fp_line
			(start 0.12065 0.3048)
			(end 0.67945 0.3048)
			(stroke
				(width 0.1)
				(type default)
			)
			(layer "B.Fab")
		)
		(fp_line
			(start 0.67945 -0.305054)
			(end 0.12065 -0.305054)
			(stroke
				(width 0.1)
				(type default)
			)
			(layer "B.Fab")
		)
		(fp_line
			(start 0.67945 0.3048)
			(end 0.67945 -0.305054)
			(stroke
				(width 0.1)
				(type default)
			)
			(layer "B.Fab")
		)
		(pad "1" smd circle
			(at 0.40005 0 180)
			(size 0 0)
			(layers "B.Cu" "B.Mask" "B.Paste")
			(net "FM_REMOTE_DEBUG_DET_R")
		)
		(pad "2" smd circle
			(at -0.40005 0 180)
			(size 0 0)
			(layers "B.Cu" "B.Mask" "B.Paste")
			(net "FM_REMOTE_DEBUG_DET")
		)
	)
	(footprint ""
		(layer "B.Cu")
		(at 315.110622 -55.235348 180)
		(property "Reference" "R1201"
			(at 0 0 0)
			(layer "B.SilkS")
			(hide yes)
			(effects
				(font
					(size 1.27 1.27)
				)
				(justify mirror)
			)
		)
		(property "Value" ""
			(at 0 0 0)
			(layer "B.Fab")
			(effects
				(font
					(size 1.27 1.27)
				)
				(justify mirror)
			)
		)
		(duplicate_pad_numbers_are_jumpers no)
		(fp_line
			(start 0.7874 0.4064)
			(end 0.7874 -0.4064)
			(stroke
				(width 0.1524)
				(type default)
			)
			(layer "B.SilkS")
		)
		(fp_line
			(start 0.7874 -0.4064)
			(end -0.7874 -0.4064)
			(stroke
				(width 0.1524)
				(type default)
			)
			(layer "B.SilkS")
		)
		(fp_line
			(start -0.7874 0.4064)
			(end 0.7874 0.4064)
			(stroke
				(width 0.1524)
				(type default)
			)
			(layer "B.SilkS")
		)
		(fp_line
			(start -0.7874 -0.4064)
			(end -0.7874 0.4064)
			(stroke
				(width 0.1524)
				(type default)
			)
			(layer "B.SilkS")
		)
		(fp_line
			(start 0.67945 0.3048)
			(end 0.67945 -0.305054)
			(stroke
				(width 0.1)
				(type default)
			)
			(layer "B.Fab")
		)
		(fp_line
			(start 0.67945 -0.305054)
			(end 0.12065 -0.305054)
			(stroke
				(width 0.1)
				(type default)
			)
			(layer "B.Fab")
		)
		(fp_line
			(start 0.12065 0.3048)
			(end 0.67945 0.3048)
			(stroke
				(width 0.1)
				(type default)
			)
			(layer "B.Fab")
		)
		(fp_line
			(start 0.12065 0.2794)
			(end 0.12065 0.3048)
			(stroke
				(width 0.1)
				(type default)
			)
			(layer "B.Fab")
		)
		(fp_line
			(start 0.12065 -0.2794)
			(end -0.12065 -0.2794)
			(stroke
				(width 0.1)
				(type default)
			)
			(layer "B.Fab")
		)
		(fp_line
			(start 0.12065 -0.305054)
			(end 0.12065 -0.2794)
			(stroke
				(width 0.1)
				(type default)
			)
			(layer "B.Fab")
		)
		(fp_line
			(start -0.120396 0.3048)
			(end -0.120396 0.2794)
			(stroke
				(width 0.1)
				(type default)
			)
			(layer "B.Fab")
		)
		(fp_line
			(start -0.120396 0.2794)
			(end 0.12065 0.2794)
			(stroke
				(width 0.1)
				(type default)
			)
			(layer "B.Fab")
		)
		(fp_line
			(start -0.12065 -0.2794)
			(end -0.12065 -0.3048)
			(stroke
				(width 0.1)
				(type default)
			)
			(layer "B.Fab")
		)
		(fp_line
			(start -0.12065 -0.3048)
			(end -0.67945 -0.3048)
			(stroke
				(width 0.1)
				(type default)
			)
			(layer "B.Fab")
		)
		(fp_line
			(start -0.67945 0.3048)
			(end -0.120396 0.3048)
			(stroke
				(width 0.1)
				(type default)
			)
			(layer "B.Fab")
		)
		(fp_line
			(start -0.67945 -0.3048)
			(end -0.67945 0.3048)
			(stroke
				(width 0.1)
				(type default)
			)
			(layer "B.Fab")
		)
		(pad "1" smd circle
			(at 0.40005 0)
			(size 0 0)
			(layers "B.Cu" "B.Mask" "B.Paste")
			(net "FM_PCH_TRIGGER1_N")
		)
		(pad "2" smd circle
			(at -0.40005 0)
			(size 0 0)
			(layers "B.Cu" "B.Mask" "B.Paste")
			(net "FM_PCH_TRIGGER1_R_N")
		)
	)
)
